FILE_TYPE = CONNECTIVITY;
{Allegro Design Entry HDL 17.2-2016 S081 (4005846) 1/11/2022}
"PAGE_NUMBER" = 142;
0"NC";
1"GND\g";
2"GND\g";
3"P5E_CPU0_PE3_TX_C_DP<2>";
4"GPU_3V3IO_RSVD1";
5"GPU_3V3IO_RSVD3";
6"GPU_3V3IO_RSVD4";
7"P5E_CPU0_PE3_RX_DN<1>";
8"P5E_CPU0_PE3_RX_DP<1>";
9"P5E_CPU0_PE2_RX_DP<1>";
10"P5E_CPU0_PE2_RX_DN<1>";
11"P5E_CPU0_PE3_TX_C_DN<1>";
12"P5E_CPU0_PE3_TX_C_DP<1>";
13"P5E_CPU0_PE2_TX_C_DP<1>";
14"P5E_CPU0_PE2_TX_C_DN<1>";
15"P5E_CPU0_PE3_RX_DN<2>";
16"P5E_CPU0_PE3_RX_DP<2>";
17"P5E_CPU0_PE2_RX_DP<2>";
18"P5E_CPU0_PE2_RX_DN<2>";
19"RST_SWB_BIC_BUF_N";
20"P5E_CPU0_PE3_RX_DP<7>";
21"P5E_CPU0_PE3_RX_DN<7>";
22"P5E_CPU0_PE3_TX_C_DN<2>";
23"P5E_CPU0_PE2_TX_C_DN<2>";
24"P5E_CPU0_PE2_RX_DP<7>";
25"P5E_CPU0_PE3_TX_C_DP<5>";
26"P5E_CPU0_PE3_TX_C_DP<4>";
27"P5E_CPU0_PE3_TX_C_DN<4>";
28"P5E_CPU0_PE2_TX_C_DP<4>";
29"P5E_CPU0_PE2_TX_C_DN<4>";
30"FM_SWB_BIC_READY_N";
31"GPU_WP_HW_CTRL_ISO";
32"P5E_CPU0_PE3_RX_DP<5>";
33"P5E_CPU0_PE3_RX_DN<5>";
34"P5E_CPU0_PE2_RX_DP<5>";
35"P5E_CPU0_PE2_RX_DN<5>";
36"P5E_CPU0_PE3_TX_C_DN<5>";
37"P5E_CPU0_PE2_TX_C_DN<5>";
38"P5E_CPU0_PE3_RX_DP<6>";
39"P5E_CPU0_PE3_RX_DN<6>";
40"P5E_CPU0_PE2_RX_DN<6>";
41"FM_SWB_PWR_EN_R_BUF";
42"P5E_CPU0_PE2_TX_C_DN<6>";
43"P5E_CPU0_PE3_TX_C_DP<6>";
44"P5E_CPU0_PE2_TX_C_DP<6>";
45"P5E_CPU0_PE2_RX_DP<6>";
46"P5E_CPU0_PE3_TX_C_DN<6>";
47"RST_BMC_FROM_SWB_N";
48"P5E_CPU0_PE3_RX_DP<0>";
49"P5E_CPU0_PE3_RX_DN<0>";
50"P5E_CPU0_PE3_RX_DN<3>";
51"P5E_CPU0_PE3_RX_DP<3>";
52"P5E_CPU0_PE2_RX_DP<0>";
53"P5E_CPU0_PE2_RX_DN<0>";
54"P5E_CPU0_PE2_RX_DP<3>";
55"P5E_CPU0_PE2_RX_DN<3>";
56"P5E_CPU0_PE3_TX_C_DP<0>";
57"P5E_CPU0_PE3_TX_C_DN<0>";
58"P5E_CPU0_PE3_TX_C_DN<3>";
59"P5E_CPU0_PE3_TX_C_DP<3>";
60"P5E_CPU0_PE2_TX_C_DP<0>";
61"P5E_CPU0_PE2_TX_C_DP<2>";
62"P5E_CPU0_PE2_TX_C_DN<0>";
63"P5E_CPU0_PE2_TX_C_DP<3>";
64"P5E_CPU0_PE2_TX_C_DN<3>";
65"P5E_CPU0_PE2_RX_DN<4>";
66"P5E_CPU0_PE3_RX_DN<4>";
67"P5E_CPU0_PE2_TX_C_DP<7>";
68"P5E_CPU0_PE2_TX_C_DN<7>";
69"P5E_CPU0_PE3_TX_C_DP<7>";
70"P5E_CPU0_PE3_TX_C_DN<7>";
71"P5E_CPU0_PE2_RX_DN<7>";
72"P5E_CPU0_PE2_TX_C_DP<5>";
73"P5E_CPU0_PE2_RX_DP<4>";
74"P5E_CPU0_PE3_RX_DP<4>";
%"UNIVERSAL_GND"
"1","(-150,250)","0","logical_power","I1";
;
CDS_LIB"logical_power"
HDL_POWER"GND";
"A"2;
%"UNIVERSAL_GND"
"1","(4725,200)","0","logical_power","I34";
;
CDS_LIB"logical_power"
HDL_POWER"GND";
"A"1;
%"CONN112_10137002101LF"
"2","(5875,2150)","0","pure_quanta","I65";
;
PART_NUMBER"DFHSB2FR012"
PART_TYPE"THLF"
MATERIAL"IO"
LOCATION"J105"
CDS_LIB"pure_quanta"
CDS_LMAN_SYM_OUTLINE"-775,1650,775,-1650"
VALUE"CONN112_10137002-101LF"
NEEDS_NO_SIZE"TRUE"
$SEC"2"
CDS_SEC"2";
"N4"
$PN"N4"30;
"M4"
$PN"M4"1;
"N3"
$PN"N3"1;
"M3"
$PN"M3"37;
"N2"
$PN"N2"41;
"M2"
$PN"M2"1;
"N1"
$PN"N1"1;
"M1"
$PN"M1"68;
"L1"
$PN"L1"67;
"L2"
$PN"L2"42;
"L3"
$PN"L3"72;
"L4"
$PN"L4"29;
"K1"
$PN"K1"1;
"K2"
$PN"K2"44;
"K3"
$PN"K3"1;
"K4"
$PN"K4"28;
"J1"
$PN"J1"69;
"J2"
$PN"J2"1;
"J3"
$PN"J3"25;
"J4"
$PN"J4"1;
"I1"
$PN"I1"70;
"I2"
$PN"I2"43;
"I3"
$PN"I3"36;
"I4"
$PN"I4"26;
"H1"
$PN"H1"1;
"H2"
$PN"H2"46;
"H3"
$PN"H3"1;
"H4"
$PN"H4"27;
"G1"
$PN"G1"71;
"G2"
$PN"G2"1;
"G3"
$PN"G3"35;
"G4"
$PN"G4"1;
"F1"
$PN"F1"24;
"F2"
$PN"F2"40;
"F3"
$PN"F3"34;
"F4"
$PN"F4"65;
"E1"
$PN"E1"1;
"E2"
$PN"E2"45;
"E3"
$PN"E3"1;
"E4"
$PN"E4"73;
"D1"
$PN"D1"21;
"D2"
$PN"D2"1;
"D3"
$PN"D3"33;
"D4"
$PN"D4"1;
"C1"
$PN"C1"20;
"C2"
$PN"C2"39;
"C3"
$PN"C3"32;
"C4"
$PN"C4"66;
"B1"
$PN"B1"1;
"B2"
$PN"B2"38;
"B3"
$PN"B3"1;
"B4"
$PN"B4"74;
"A1"
$PN"A1"6;
"A2"
$PN"A2"1;
"A3"
$PN"A3"31;
"A4"
$PN"A4"1;
%"CONN112_10137002101LF"
"1","(950,2150)","0","pure_quanta","I68";
;
PART_NUMBER"DFHSB2FR012"
PART_TYPE"THLF"
MATERIAL"IO"
LOCATION"J105"
CDS_LIB"pure_quanta"
CDS_LMAN_SYM_OUTLINE"-775,1650,775,-1650"
NEEDS_NO_SIZE"TRUE"
VALUE"CONN112_10137002-101LF"
$SEC"1"
CDS_SEC"1";
"N8"
$PN"N8"47;
"M8"
$PN"M8"2;
"N7"
$PN"N7"2;
"M7"
$PN"M7"14;
"N6"
$PN"N6"19;
"M6"
$PN"M6"2;
"N5"
$PN"N5"2;
"M5"
$PN"M5"64;
"L5"
$PN"L5"63;
"L6"
$PN"L6"23;
"L7"
$PN"L7"13;
"L8"
$PN"L8"62;
"K5"
$PN"K5"2;
"K6"
$PN"K6"61;
"K7"
$PN"K7"2;
"K8"
$PN"K8"60;
"J5"
$PN"J5"59;
"J6"
$PN"J6"2;
"J7"
$PN"J7"12;
"J8"
$PN"J8"2;
"I5"
$PN"I5"58;
"I6"
$PN"I6"3;
"I7"
$PN"I7"11;
"I8"
$PN"I8"57;
"H5"
$PN"H5"2;
"H6"
$PN"H6"22;
"H7"
$PN"H7"2;
"H8"
$PN"H8"56;
"G5"
$PN"G5"55;
"G6"
$PN"G6"2;
"G7"
$PN"G7"10;
"G8"
$PN"G8"2;
"F5"
$PN"F5"54;
"F6"
$PN"F6"18;
"F7"
$PN"F7"9;
"F8"
$PN"F8"53;
"E5"
$PN"E5"2;
"E6"
$PN"E6"17;
"E7"
$PN"E7"2;
"E8"
$PN"E8"52;
"D5"
$PN"D5"51;
"D6"
$PN"D6"2;
"D7"
$PN"D7"8;
"D8"
$PN"D8"2;
"C5"
$PN"C5"50;
"C6"
$PN"C6"16;
"C7"
$PN"C7"7;
"C8"
$PN"C8"49;
"B5"
$PN"B5"2;
"B6"
$PN"B6"15;
"B7"
$PN"B7"2;
"B8"
$PN"B8"48;
"A5"
$PN"A5"5;
"A6"
$PN"A6"2;
"A7"
$PN"A7"4;
"A8"
$PN"A8"2;
END.
